FILE_TYPE = CONNECTIVITY;
{Allegro Design Entry HDL 16.6-p007 (v16-6-112F) 10/10/2012}
"PAGE_NUMBER" = 203;
0"NC";
1"GND\g";
2"GND\g";
3"GND\g";
4"GND\g";
5"PVCCIN_CPU0\g";
6"PVCCIN_CPU0\g";
7"GND\g";
8"GND\g";
9"GND\g";
10"GND\g";
11"PVCCIN_CPU0\g";
12"VR_FET_SW_P12V_STBY_PVCCIN_CPU0\g";
13"GND\g";
14"VR_FET_SW_P12V_STBY_PVCCIN_CPU0\g";
15"GND\g";
16"GND\g";
17"P5V_STBY\g";
18"P5V_STBY\g";
19"GND\g";
20"GND\g";
21"GND\g";
22"GND\g";
23"VR_PVCCIN_CPU0_PH4_PHASE"VOLTAGE"5";
24"VR_PVCCIN_CPU0_PH4_BOOT";
25"A_TSENSE_PVCCIN_CPU0";
26"VR_PVCCIN_CPU0_PHASE3"VOLTAGE"5";
27"VR_PVCCIN_CPU0_PH3_PHASE"VOLTAGE"5";
28"VR_PVCCIN_CPU0_PH3_BOOT";
29"VR_PVCCIN_CPU0_PWM3";
30"TP_PVCCIN_CPU0_PH4_GL_0";
31"VR_PVCCIN_CPU0_PWM4";
32"VR_PVCCIN_CPU0_PH3_BOOT_R";
33"VR_PVCCIN_CPU0_PHASE4"VOLTAGE"5";
34"NC_PVCCIN_CPU0_PH4_P31";
35"VR_PVCCIN_CPU0_AIREF4";
36"ISENSE_PVCCIN_CPU0_PH4_IMON";
37"UN$203$3D01R5F-GP$I102$2";
38"VR_PVCCIN_CPU0_PH3_VCIN";
39"VR_PVCCIN_CPU0_PH3_OCSET"VOLTAGE"3.6";
40"A_TSENSE_PVCCIN_CPU0";
41"TP_PVCCIN_CPU0_PH3_GL_1";
42"TP_PVCCIN_CPU0_PH3_GL_0";
43"VR_PVCCIN_CPU0_PH4_BOOT_R";
44"VR_PVCCIN_CPU0_PH4_VCIN"VOLTAGE"5";
45"NC_PVCCIN_CPU0_PH3_P31";
46"UN$203$3D01R5F-GP$I105$2";
47"VR_PVCCIN_CPU0_PH4_OCSET"VOLTAGE"3.6";
48"TP_PVCCIN_CPU0_PH4_GL_1";
49"VR_PVCCIN_CPU0_AIREF3";
50"ISENSE_PVCCIN_CPU0_PH3_IMON";
%"CAP"
"1","(-6850,4175)","0","mstr_discrete","I1";
;
CDS_SEC"1"
CDS_LOCATION"C6P24"
CDS_LIB"mstr_discrete"
ROOM"PVCCIN_CPU0_PWR_VR"
SEC_TYPE"0805"
SEC"1"
PACK_TYPE"0805"
PART_NUMBER"C95333-007"
MATERIAL"X6S"
VOLTAGE"16V"
TOLERANCE"10%"
VALUE"10UF"
LOCATION"C6P24";
"A"
$PN"1"12;
"B"
$PN"2"13;
%"GND"
"1","(-2200,3750)","0","mstr_symbols","I100";
;
ROOM"VDDQ_KLM_PWR_VR"
VOLTAGE"0"
SIZE"1B"
CDS_LIB"mstr_symbols"
BODY_TYPE"PLUMBING"
HDL_POWER"GND";
"A\NAC"1;
%"SC2K2P50V3KX-GP"
"1","(-2100,3475)","0","w_hdl","I101";
;
CDS_SEC"1"
$SEC"1"
CDS_LOCATION"CT38"
PACK_TYPE"SMD-BCG6"
PART_NUMBER"78.22224.2BL"
CDS_LMAN_SYM_OUTLINE"-50,25,50,-25"
CDS_LIB"w_hdl"
STATUS"NOPOP"
LOCATION"CT38"
VALUE"SC2K2P50V3KX-GP";
"2"
$PN"2"37;
"1"
$PN"1"26;
%"3D01R5F-GP"
"1","(-2100,3200)","4","w_hdl","I102";
;
CDS_SEC"1"
$SEC"1"
CDS_LOCATION"RT26"
CDS_LMAN_SYM_OUTLINE"-50,75,50,-75"
CDS_LIB"w_hdl"
PART_NUMBER"64.3R015.16L"
PACK_TYPE"SMD-RG5"
LOCATION"RT26"
VALUE"3D01R5F-GP"
STATUS"NOPOP";
"2"
$PN"2"37;
"1"
$PN"1"2;
%"GND"
"1","(-2100,2975)","0","mstr_symbols","I103";
;
CDS_LIB"mstr_symbols"
ROOM"PVCCIN_CPU0_PWR_VR"
BOM_COST"PROC_VRD_VCCIN_CPU0"
VOLTAGE"0"
SIZE"1B"
BODY_TYPE"PLUMBING"
HDL_POWER"GND";
"A\NAC"2;
%"GND"
"1","(-2100,375)","0","mstr_symbols","I104";
;
HDL_POWER"GND"
BODY_TYPE"PLUMBING"
ROOM"PVCCIN_CPU0_PWR_VR"
BOM_COST"PROC_VRD_VCCIN_CPU0"
VOLTAGE"0"
SIZE"1B"
CDS_LIB"mstr_symbols";
"A\NAC"3;
%"3D01R5F-GP"
"1","(-2100,575)","4","w_hdl","I105";
;
CDS_SEC"1"
$SEC"1"
CDS_LOCATION"RT27"
PACK_TYPE"SMD-RG5"
PART_NUMBER"64.3R015.16L"
CDS_LIB"w_hdl"
CDS_LMAN_SYM_OUTLINE"-50,75,50,-75"
STATUS"NOPOP"
VALUE"3D01R5F-GP"
LOCATION"RT27";
"2"
$PN"2"46;
"1"
$PN"1"3;
%"SC2K2P50V3KX-GP"
"1","(-2100,800)","0","w_hdl","I106";
;
CDS_SEC"1"
$SEC"1"
CDS_LOCATION"CT41"
CDS_LIB"w_hdl"
CDS_LMAN_SYM_OUTLINE"-50,25,50,-25"
PACK_TYPE"SMD-BCG6"
PART_NUMBER"78.22224.2BL"
STATUS"NOPOP"
VALUE"SC2K2P50V3KX-GP"
LOCATION"CT41";
"2"
$PN"2"46;
"1"
$PN"1"33;
%"GND"
"1","(-2150,1050)","0","mstr_symbols","I107";
;
HDL_POWER"GND"
BODY_TYPE"PLUMBING"
CDS_LIB"mstr_symbols"
ROOM"VDDQ_KLM_PWR_VR"
VOLTAGE"0"
SIZE"1B";
"A\NAC"4;
%"CAP"
"1","(-2150,1250)","0","mstr_discrete","I108";
;
CDS_SEC"1"
$SEC"1"
CDS_LOCATION"CT42"
ROOM"VDDQ_KLM_PWR_VR"
CDS_LIB"mstr_discrete"
VOLTAGE"50V"
TOLERANCE"10%"
MATERIAL"X7R"
PART_NUMBER"A36096-046"
PACK_TYPE"0402LF"
STATUS"NOPOP"
LOCATION"CT42"
VALUE"1000PF";
"A"
$PN"1"25;
"B"
$PN"2"4;
%"PVCCIN_CPU0"
"1","(-750,1050)","0","mstr_symbols","I109";
;
CDS_LIB"mstr_symbols"
VOLTAGE"2.0V"
BODY_TYPE"PLUMBING"
HDL_POWER"PVCCIN_CPU0";
"G\NAC"5;
%"RES"
"1","(-4950,3700)","0","mstr_discrete","I110";
;
CDS_SEC"1"
$SEC"1"
CDS_LOCATION"RT25"
CDS_LIB"mstr_discrete"
BOM_COST"DEBUG"
ROOM"BMC_DEBUG_HEADER"
MATERIAL"CHIP"
WATTAGE"1/16W"
VALUE"0.0"
TOLERANCE"5%"
PART_NUMBER"G21497-005"
LOCATION"RT25"
PACK_TYPE"0402";
"B"
$PN"2"32;
"A"
$PN"1"28;
%"RES"
"1","(-5175,950)","0","mstr_discrete","I111";
;
CDS_SEC"1"
$SEC"1"
CDS_LOCATION"RT28"
ROOM"BMC_DEBUG_HEADER"
BOM_COST"DEBUG"
CDS_LIB"mstr_discrete"
LOCATION"RT28"
TOLERANCE"5%"
MATERIAL"CHIP"
PACK_TYPE"0402"
PART_NUMBER"G21497-005"
VALUE"0.0"
WATTAGE"1/16W";
"B"
$PN"2"43;
"A"
$PN"1"24;
%"PVCCIN_CPU0"
"1","(-750,3725)","0","mstr_symbols","I12";
;
VOLTAGE"2.0V"
CDS_LIB"mstr_symbols"
BODY_TYPE"PLUMBING"
HDL_POWER"PVCCIN_CPU0";
"G\NAC"6;
%"GND"
"1","(-1025,3075)","0","mstr_symbols","I14";
;
ROOM"PVCCIN_CPU0_PWR_VR"
BOM_COST"PROC_VRD_VCCIN_CPU0"
CDS_LIB"mstr_symbols"
VOLTAGE"0"
SIZE"1B"
BODY_TYPE"PLUMBING"
HDL_POWER"GND";
"A\NAC"7;
%"INDUCTOR"
"1","(-1550,3625)","0","mstr_discrete","I15";
;
ROOM"PVCCIN_CPU0_PWR_VR"
CDS_LOCATION"L4D2"
CDS_LIB"mstr_discrete"
$SEC"1"
CDS_SEC"1"
PACK_TYPE"SM"
LOCATION"L4D2"
VALUE"0.12UH"
MATERIAL"IND"
PART_NUMBER"D92183-034";
"INA\NAC"
$PN"1"26;
"INB\NAC"
$PN"2"6;
%"CAPP"
"1","(-1150,2575)","0","mstr_discrete","I16";
;
CDS_SEC"1"
VOLTAGE"2.5V"
CDS_LIB"mstr_discrete"
CDS_LOCATION"C6R3"
BOM_COST"PROC_VRD_VCCIN_CPU0"
ROOM"PVCCIN_CPU0_DECAP_VR"
SEC"1"
SEC_TYPE"3018"
PACK_TYPE"3018"
MATERIAL"ALUM"
TOLERANCE"20%"
VALUE"470UF"
PART_NUMBER"699013-049"
LOCATION"C6R3";
"B"
$PN"2"8;
"A"
$PN"1"11;
%"GND"
"1","(-700,2200)","0","mstr_symbols","I17";
;
ROOM"PVCCIN_CPU0_DECAP_VR"
BOM_COST"PROC_VRD_VCCIN_CPU0"
SIZE"1B"
CDS_LIB"mstr_symbols"
VOLTAGE"0"
BODY_TYPE"PLUMBING"
HDL_POWER"GND";
"A\NAC"8;
%"CAPP"
"1","(-1625,2575)","0","mstr_discrete","I18";
;
CDS_SEC"1"
VOLTAGE"2.5V"
CDS_LIB"mstr_discrete"
CDS_LOCATION"C6R9"
ROOM"PVCCIN_CPU0_DECAP_VR"
BOM_COST"PROC_VRD_VCCIN_CPU0"
SEC"1"
SEC_TYPE"3018"
VALUE"470UF"
MATERIAL"ALUM"
PACK_TYPE"3018"
TOLERANCE"20%"
PART_NUMBER"699013-049"
LOCATION"C6R9";
"B"
$PN"2"8;
"A"
$PN"1"11;
%"CAP"
"1","(-7125,4150)","0","mstr_discrete","I2";
;
CDS_SEC"1"
CDS_LOCATION"C6R6"
CDS_LIB"mstr_discrete"
SEC_TYPE"0805"
SEC"1"
ROOM"PVCCIN_CPU0_PWR_VR"
PACK_TYPE"0805"
MATERIAL"X6S"
PART_NUMBER"C95333-007"
VOLTAGE"16V"
LOCATION"C6R6"
VALUE"10UF"
TOLERANCE"10%";
"A"
$PN"1"12;
"B"
$PN"2"13;
%"INDUCTOR"
"1","(-1650,900)","0","mstr_discrete","I24";
;
CDS_SEC"1"
$SEC"1"
ROOM"PVCCIN_CPU0_PWR_VR"
CDS_LIB"mstr_discrete"
CDS_LOCATION"L4D1"
MATERIAL"IND"
PACK_TYPE"SM"
PART_NUMBER"D92183-034"
VALUE"0.12UH"
LOCATION"L4D1";
"INA\NAC"
$PN"1"33;
"INB\NAC"
$PN"2"5;
%"CAP_A"
"1","(-1025,600)","0","dev_discrete","I25";
;
CDS_LIB"dev_discrete"
ROOM"PVCCIN_CPU0_PWR_VR"
SEC"1"
SEC_TYPE"0603V"
CDS_SEC"1"
BOM_COST"PROC_VRD_VCCIN_CPU0"
CDS_LOCATION"C6P3"
VOLTAGE"4V"
MATERIAL"X6S"
PACK_TYPE"0603V"
LOCATION"C6P3"
VALUE"22.0UF"
TOLERANCE"20%"
PART_NUMBER"E15431-004";
"B"
$PN"2"9;
"A"
$PN"1"5;
%"GND"
"1","(-1025,350)","0","mstr_symbols","I26";
;
ROOM"PVCCIN_CPU0_PWR_VR"
BOM_COST"PROC_VRD_VCCIN_CPU0"
CDS_LIB"mstr_symbols"
VOLTAGE"0"
SIZE"1B"
BODY_TYPE"PLUMBING"
HDL_POWER"GND";
"A\NAC"9;
%"GND"
"1","(-2700,3250)","0","mstr_symbols","I27";
;
ROOM"PVCCIN_CPU0_PWR_VR"
BOM_COST"PROC_VRD_VCCIN_CPU0"
VOLTAGE"0"
SIZE"1B"
CDS_LIB"mstr_symbols"
BODY_TYPE"PLUMBING"
HDL_POWER"GND";
"A\NAC"10;
%"CAPP"
"1","(-2075,2550)","0","mstr_discrete","I28";
;
CDS_SEC"1"
CDS_LIB"mstr_discrete"
VOLTAGE"2.5V"
ROOM"PVCCIN_CPU0_DECAP_VR"
CDS_LOCATION"C6P23"
SEC"1"
BOM_COST"PROC_VRD_VCCIN_CPU0"
SEC_TYPE"3018"
PART_NUMBER"699013-049"
LOCATION"C6P23"
PACK_TYPE"3018"
MATERIAL"ALUM"
TOLERANCE"20%"
VALUE"470UF";
"B"
$PN"2"8;
"A"
$PN"1"11;
%"CAPP"
"1","(-2525,2575)","0","mstr_discrete","I29";
;
CDS_SEC"1"
VOLTAGE"2.5V"
CDS_LIB"mstr_discrete"
CDS_LOCATION"C6P14"
ROOM"PVCCIN_CPU0_DECAP_VR"
BOM_COST"PROC_VRD_VCCIN_CPU0"
SEC"1"
SEC_TYPE"3018"
LOCATION"C6P14"
TOLERANCE"20%"
MATERIAL"ALUM"
PART_NUMBER"699013-049"
VALUE"470UF"
PACK_TYPE"3018";
"B"
$PN"2"8;
"A"
$PN"1"11;
%"CAP"
"1","(-6100,800)","2","mstr_discrete","I3";
;
CDS_SEC"1"
CDS_LIB"mstr_discrete"
CDS_LOCATION"C4D9"
ROOM"PVCCIN_CPU0_PWR_VR"
SPOF"TRUE"
SEC_TYPE"0402"
SEC"1"
NO_XNET_CONNECTION"1"
PART_NUMBER"A36096-104"
MATERIAL"X7R"
VALUE"0.220UF"
LOCATION"C4D9"
TOLERANCE"10%"
VOLTAGE"16V"
PACK_TYPE"0402";
"A"
$PN"1"24;
"B"
$PN"2"23;
%"CAPP"
"1","(-2975,2575)","0","mstr_discrete","I30";
;
CDS_SEC"1"
VOLTAGE"2.5V"
CDS_LIB"mstr_discrete"
ROOM"PVCCIN_CPU0_DECAP_VR"
CDS_LOCATION"C6P18"
BOM_COST"PROC_VRD_VCCIN_CPU0"
SEC"1"
SEC_TYPE"3018"
MATERIAL"ALUM"
PACK_TYPE"3018"
TOLERANCE"20%"
PART_NUMBER"699013-049"
VALUE"470UF"
LOCATION"C6P18";
"B"
$PN"2"8;
"A"
$PN"1"11;
%"CAPP"
"1","(-3425,2575)","0","mstr_discrete","I32";
;
CDS_SEC"1"
VOLTAGE"2.5V"
CDS_LIB"mstr_discrete"
CDS_LOCATION"C6P8"
ROOM"PVCCIN_CPU0_DECAP_VR"
BOM_COST"PROC_VRD_VCCIN_CPU0"
SEC"1"
SEC_TYPE"3018"
MATERIAL"ALUM"
PACK_TYPE"3018"
LOCATION"C6P8"
PART_NUMBER"699013-049"
TOLERANCE"20%"
VALUE"470UF";
"B"
$PN"2"8;
"A"
$PN"1"11;
%"PVCCIN_CPU0"
"1","(-3850,2850)","0","mstr_symbols","I33";
;
VOLTAGE"2.0V"
CDS_LIB"mstr_symbols"
BODY_TYPE"PLUMBING"
HDL_POWER"PVCCIN_CPU0";
"G\NAC"11;
%"CAPP"
"1","(-3850,2575)","0","mstr_discrete","I34";
;
CDS_SEC"1"
CDS_LIB"mstr_discrete"
ROOM"PVCCIN_CPU0_DECAP_VR"
CDS_LOCATION"C6N9"
SEC"1"
BOM_COST"PROC_VRD_VCCIN_CPU0"
SEC_TYPE"3018"
MATERIAL"ALUM"
VOLTAGE"2.5V"
PACK_TYPE"3018"
TOLERANCE"20%"
VALUE"470UF"
LOCATION"C6N9"
PART_NUMBER"699013-049";
"B"
$PN"2"8;
"A"
$PN"1"11;
%"RES"
"1","(-5850,4725)","0","mstr_discrete","I38";
;
CDS_SEC"1"
SEC_TYPE"0402"
CDS_LOCATION"R6P19"
SEC"1"
ROOM"PVCCIN_CPU0_PWR_VR"
CDS_LIB"mstr_discrete"
WATTAGE"1/16W"
PACK_TYPE"0402"
TOLERANCE"1%"
VALUE"1.0"
LOCATION"R6P19"
MATERIAL"CHIP"
PART_NUMBER"G21796-090";
"B"
$PN"2"17;
"A"
$PN"1"38;
%"VCC_CORE"
"1","(-7425,4600)","0","mstr_symbols","I39";
;
CDS_LIB"mstr_symbols"
HDL_POWER"VR_FET_SW_P12V_STBY_PVCCIN_CPU0";
"A"12;
%"CAP"
"1","(-5300,4125)","0","mstr_discrete","I40";
;
CDS_SEC"1"
ROOM"PVCCIN_CPU0_PWR_VR"
CDS_LOCATION"C4D13"
SEC"1"
CDS_LIB"mstr_discrete"
SEC_TYPE"0402"
MATERIAL"X7R"
PACK_TYPE"0402"
PART_NUMBER"A36096-155"
VOLTAGE"16V"
VALUE"0.22UF"
LOCATION"C4D13"
TOLERANCE"10%";
"A"
$PN"1"17;
"B"
$PN"2"13;
%"CAP_A"
"1","(-5450,4150)","2","dev_discrete","I41";
;
SEC_TYPE"0402V"
CDS_LIB"dev_discrete"
CDS_SEC"1"
CDS_LOCATION"C4D14"
SEC"1"
ROOM"PVCCIN_CPU0_PWR_VR"
PART_NUMBER"D97712-004"
PACK_TYPE"0402V"
MATERIAL"X6S"
VALUE"1.0UF"
LOCATION"C4D14"
VOLTAGE"6.3V"
TOLERANCE"10%";
"B"
$PN"2"13;
"A"
$PN"1"17;
%"CAP"
"1","(-6025,3525)","2","mstr_discrete","I42";
;
CDS_SEC"1"
CDS_LIB"mstr_discrete"
SEC_TYPE"0402"
SPOF"TRUE"
SEC"1"
CDS_LOCATION"C4D28"
ROOM"PVCCIN_CPU0_PWR_VR"
NO_XNET_CONNECTION"1"
PART_NUMBER"A36096-104"
VALUE"0.220UF"
MATERIAL"X7R"
TOLERANCE"10%"
PACK_TYPE"0402"
VOLTAGE"16V"
LOCATION"C4D28";
"A"
$PN"1"28;
"B"
$PN"2"27;
%"CAP"
"1","(-6075,4125)","0","mstr_discrete","I45";
;
CDS_SEC"1"
ROOM"PVCCIN_CPU0_PWR_VR"
CDS_LOCATION"C4D16"
CDS_LIB"mstr_discrete"
SEC"1"
SEC_TYPE"0402"
PACK_TYPE"0402"
TOLERANCE"10%"
VOLTAGE"16V"
VALUE"1.0UF"
LOCATION"C4D16"
MATERIAL"X6S"
PART_NUMBER"D97712-011";
"A"
$PN"1"38;
"B"
$PN"2"13;
%"CAP_A"
"1","(-6350,4150)","0","dev_discrete","I46";
;
CDS_LIB"dev_discrete"
CDS_LOCATION"C4D35"
CDS_SEC"1"
ROOM"PVCCIN_CPU0_PWR_VR"
SEC_TYPE"0402V"
SEC"1"
PART_NUMBER"A36096-030"
MATERIAL"X7R"
PACK_TYPE"0402V"
LOCATION"C4D35"
TOLERANCE"10%"
VALUE"0.1UF"
VOLTAGE"16V";
"B"
$PN"2"13;
"A"
$PN"1"12;
%"CAP"
"1","(-6600,4150)","0","mstr_discrete","I47";
;
CDS_SEC"1"
CDS_LOCATION"C4D30"
CDS_LIB"mstr_discrete"
SEC_TYPE"0402"
SEC"1"
ROOM"PVCCIN_CPU0_PWR_VR"
MATERIAL"X6S"
PACK_TYPE"0402"
PART_NUMBER"D97712-011"
VOLTAGE"16V"
TOLERANCE"10%"
VALUE"1.0UF"
LOCATION"C4D30";
"A"
$PN"1"12;
"B"
$PN"2"13;
%"CAP"
"1","(-5525,1475)","0","mstr_discrete","I48";
;
CDS_SEC"1"
CDS_LIB"mstr_discrete"
ROOM"PVCCIN_CPU0_PWR_VR"
CDS_LOCATION"C4D5"
SEC"1"
SEC_TYPE"0402"
TOLERANCE"10%"
VOLTAGE"16V"
MATERIAL"X7R"
PACK_TYPE"0402"
VALUE"0.22UF"
LOCATION"C4D5"
PART_NUMBER"A36096-155";
"A"
$PN"1"18;
"B"
$PN"2"15;
%"CAP_A"
"1","(-5650,1475)","2","dev_discrete","I49";
;
CDS_LIB"dev_discrete"
CDS_LOCATION"C4D6"
CDS_SEC"1"
SEC_TYPE"0402V"
SEC"1"
ROOM"PVCCIN_CPU0_PWR_VR"
PART_NUMBER"D97712-004"
PACK_TYPE"0402V"
MATERIAL"X6S"
VOLTAGE"6.3V"
VALUE"1.0UF"
LOCATION"C4D6"
TOLERANCE"10%";
"B"
$PN"2"15;
"A"
$PN"1"18;
%"RES"
"1","(-5900,1975)","0","mstr_discrete","I50";
;
CDS_SEC"1"
CDS_LIB"mstr_discrete"
CDS_LOCATION"R6P10"
SEC_TYPE"0402"
SEC"1"
ROOM"PVCCIN_CPU0_PWR_VR"
LOCATION"R6P10"
VALUE"1.0"
TOLERANCE"1%"
WATTAGE"1/16W"
PART_NUMBER"G21796-090"
PACK_TYPE"0402"
MATERIAL"CHIP";
"B"
$PN"2"18;
"A"
$PN"1"44;
%"CAP"
"1","(-6225,1450)","0","mstr_discrete","I51";
;
CDS_SEC"1"
CDS_LIB"mstr_discrete"
ROOM"PVCCIN_CPU0_PWR_VR"
CDS_LOCATION"C4D7"
SEC"1"
SEC_TYPE"0402"
VOLTAGE"16V"
PACK_TYPE"0402"
TOLERANCE"10%"
VALUE"1.0UF"
LOCATION"C4D7"
MATERIAL"X6S"
PART_NUMBER"D97712-011";
"A"
$PN"1"44;
"B"
$PN"2"15;
%"CAP_A"
"1","(-6475,1450)","0","dev_discrete","I52";
;
CDS_LIB"dev_discrete"
ROOM"PVCCIN_CPU0_PWR_VR"
CDS_LOCATION"C4D11"
CDS_SEC"1"
SEC_TYPE"0402V"
SEC"1"
MATERIAL"X7R"
PACK_TYPE"0402V"
TOLERANCE"10%"
PART_NUMBER"A36096-030"
VALUE"0.1UF"
LOCATION"C4D11"
VOLTAGE"16V";
"B"
$PN"2"15;
"A"
$PN"1"14;
%"CAP"
"1","(-6700,1400)","0","mstr_discrete","I53";
;
CDS_SEC"1"
CDS_LIB"mstr_discrete"
CDS_LOCATION"C4D10"
SEC_TYPE"0402"
SEC"1"
ROOM"PVCCIN_CPU0_PWR_VR"
PACK_TYPE"0402"
TOLERANCE"10%"
MATERIAL"X6S"
VOLTAGE"16V"
VALUE"1.0UF"
PART_NUMBER"D97712-011"
LOCATION"C4D10";
"A"
$PN"1"14;
"B"
$PN"2"15;
%"CAP"
"1","(-7425,4150)","0","mstr_discrete","I54";
;
CDS_SEC"1"
CDS_LIB"mstr_discrete"
SEC_TYPE"0805"
SEC"1"
CDS_LOCATION"C6P19"
ROOM"PVCCIN_CPU0_PWR_VR"
MATERIAL"X6S"
PACK_TYPE"0805"
PART_NUMBER"C95333-007"
VOLTAGE"16V"
TOLERANCE"10%"
VALUE"10UF"
LOCATION"C6P19";
"A"
$PN"1"12;
"B"
$PN"2"13;
%"GND"
"1","(-7425,3750)","0","mstr_symbols","I56";
;
ROOM"PVCCIN_CPU0_PWR_VR"
BOM_COST"PROC_VRD_VCCIN_CPU0"
VOLTAGE"0"
CDS_LIB"mstr_symbols"
SIZE"1B"
BODY_TYPE"PLUMBING"
HDL_POWER"GND";
"A\NAC"13;
%"CAP"
"1","(-6950,1400)","0","mstr_discrete","I57";
;
CDS_SEC"1"
CDS_LIB"mstr_discrete"
CDS_LOCATION"C6P20"
SEC_TYPE"0805"
SEC"1"
ROOM"PVCCIN_CPU0_PWR_VR"
PACK_TYPE"0805"
TOLERANCE"10%"
VOLTAGE"16V"
MATERIAL"X6S"
LOCATION"C6P20"
VALUE"10UF"
PART_NUMBER"C95333-007";
"A"
$PN"1"14;
"B"
$PN"2"15;
%"CAP"
"1","(-7200,1450)","0","mstr_discrete","I58";
;
CDS_SEC"1"
CDS_LIB"mstr_discrete"
SEC_TYPE"0805"
SEC"1"
CDS_LOCATION"C6P15"
ROOM"PVCCIN_CPU0_PWR_VR"
PACK_TYPE"0805"
VALUE"10UF"
TOLERANCE"10%"
VOLTAGE"16V"
MATERIAL"X6S"
PART_NUMBER"C95333-007"
LOCATION"C6P15";
"A"
$PN"1"14;
"B"
$PN"2"15;
%"CAP"
"1","(-7475,1450)","0","mstr_discrete","I59";
;
CDS_SEC"1"
CDS_LIB"mstr_discrete"
SEC_TYPE"0805"
SEC"1"
CDS_LOCATION"C6P7"
ROOM"PVCCIN_CPU0_PWR_VR"
MATERIAL"X6S"
VOLTAGE"16V"
PACK_TYPE"0805"
TOLERANCE"10%"
VALUE"10UF"
LOCATION"C6P7"
PART_NUMBER"C95333-007";
"A"
$PN"1"14;
"B"
$PN"2"15;
%"VCC_CORE"
"1","(-7475,1900)","0","mstr_symbols","I61";
;
CDS_LIB"mstr_symbols"
HDL_POWER"VR_FET_SW_P12V_STBY_PVCCIN_CPU0";
"A"14;
%"GND"
"1","(-7475,1025)","0","mstr_symbols","I62";
;
SIZE"1B"
ROOM"PVCCIN_CPU0_PWR_VR"
BOM_COST"PROC_VRD_VCCIN_CPU0"
CDS_LIB"mstr_symbols"
VOLTAGE"0"
BODY_TYPE"PLUMBING"
HDL_POWER"GND";
"A\NAC"15;
%"GND"
"1","(-2775,500)","0","mstr_symbols","I63";
;
ROOM"PVCCIN_CPU0_PWR_VR"
BOM_COST"PROC_VRD_VCCIN_CPU0"
SIZE"1B"
CDS_LIB"mstr_symbols"
VOLTAGE"0"
BODY_TYPE"PLUMBING"
HDL_POWER"GND";
"A\NAC"16;
%"P5V_STBY"
"1","(-4625,4850)","0","mstr_symbols","I64";
;
VOLTAGE"5.0V"
CDS_LIB"mstr_symbols"
SIZE"1B"
BODY_TYPE"PLUMBING"
HDL_POWER"P5V_STBY";
"G\NAC"17;
%"P5V_STBY"
"1","(-4600,2100)","0","mstr_symbols","I65";
;
SIZE"1B"
CDS_LIB"mstr_symbols"
VOLTAGE"5.0V"
BODY_TYPE"PLUMBING"
HDL_POWER"P5V_STBY";
"G\NAC"18;
%"CAP_A"
"1","(-1025,3375)","0","dev_discrete","I66";
;
CDS_LIB"dev_discrete"
CDS_SEC"1"
CDS_LOCATION"C6P21"
ROOM"PVCCIN_CPU0_PWR_VR"
SEC"1"
SEC_TYPE"0603V"
BOM_COST"PROC_VRD_VCCIN_CPU0"
MATERIAL"X6S"
VOLTAGE"4V"
PACK_TYPE"0603V"
TOLERANCE"20%"
VALUE"22.0UF"
LOCATION"C6P21"
PART_NUMBER"E15431-004";
"B"
$PN"2"7;
"A"
$PN"1"6;
%"RES"
"2","(-700,2525)","0","mstr_discrete","I67";
;
CDS_SEC"1"
CDS_LIB"mstr_discrete"
ROOM"PVCCIN_CPU0_DECAP_VR"
CDS_LOCATION"R4E13"
SEC"1"
BOM_COST"PROC_VRD_VCCIN_CPU0"
SEC_TYPE"0603"
PACK_TYPE"0603"
MATERIAL"CHIP"
WATTAGE"1/10W"
TOLERANCE"1%"
VALUE"100.0"
PART_NUMBER"G22026-038"
LOCATION"R4E13";
"A"
$PN"1"11;
"B"
$PN"2"8;
%"CAP_A"
"1","(-750,3375)","0","dev_discrete","I68";
;
CDS_SEC"1"
CDS_LIB"dev_discrete"
CDS_LOCATION"C4D34"
SEC"1"
SEC_TYPE"0603V"
PACK_TYPE"0603V"
MATERIAL"X6S"
TOLERANCE"20%"
VOLTAGE"4V"
LOCATION"C4D34"
PART_NUMBER"E15431-004"
VALUE"22.0UF";
"B"
$PN"2"7;
"A"
$PN"1"6;
%"CAP_A"
"1","(-750,575)","0","dev_discrete","I69";
;
CDS_SEC"1"
CDS_LIB"dev_discrete"
CDS_LOCATION"C4D4"
SEC_TYPE"0603V"
SEC"1"
PACK_TYPE"0603V"
TOLERANCE"20%"
PART_NUMBER"E15431-004"
MATERIAL"X6S"
LOCATION"C4D4"
VALUE"22.0UF"
VOLTAGE"4V";
"B"
$PN"2"9;
"A"
$PN"1"5;
%"IR354XX"
"1","(-3325,3900)","0","mstr_discrete","I70";
;
CDS_SEC"1"
CDS_LIB"mstr_discrete"
CDS_LOCATION"EU4D3"
SEC"1"
SEC_TYPE"SM"
PACK_TYPE"SM"
PART_NUMBER"H73688-001"
MATERIAL"IC"
LOCATION"EU4D3"
VALUE"IR35411";
"TOUT_FLT"
$PN"36"40;
"NC"
$PN"31"45;
"OCSET"
$PN"37"39;
"IOUT"
$PN"38"50;
"SW"
$PN"10"26;
"BOOST"
$PN"33"32;
"REFIN"
$PN"39"49;
"PWM"
$PN"34"29;
"PHASE"
$PN"32"27;
"VIN<0>"
$PN"25"12;
"VCC"
$PN"3"38;
"VIN<1>"
$PN"30"12;
"EN"
$PN"35"17;
"VDRV"
$PN"4"17;
"VOS"
$PN"1"6;
"LGND"
$PN"2"10;
"PGND<1>"
$PN"7"10;
"PGND<2>"
$PN"40"10;
"PGND<0>"
$PN"5"10;
"GL<0>"
$PN"6"42;
"GL<1>"
$PN"41"41;
%"IR354XX"
"1","(-3350,1175)","0","mstr_discrete","I71";
;
PACK_TYPE"SM"
CDS_SEC"1"
$SEC"1"
CDS_LIB"mstr_discrete"
CDS_LOCATION"EU4D1"
MATERIAL"IC"
LOCATION"EU4D1"
VALUE"IR35411"
PART_NUMBER"H73688-001";
"TOUT_FLT"
$PN"36"25;
"NC"
$PN"31"34;
"OCSET"
$PN"37"47;
"IOUT"
$PN"38"36;
"SW"
$PN"10"33;
"BOOST"
$PN"33"43;
"REFIN"
$PN"39"35;
"PWM"
$PN"34"31;
"PHASE"
$PN"32"23;
"VIN<0>"
$PN"25"14;
"VCC"
$PN"3"44;
"VIN<1>"
$PN"30"14;
"EN"
$PN"35"18;
"VDRV"
$PN"4"18;
"VOS"
$PN"1"5;
"LGND"
$PN"2"16;
"PGND<1>"
$PN"7"16;
"PGND<2>"
$PN"40"16;
"PGND<0>"
$PN"5"16;
"GL<0>"
$PN"6"30;
"GL<1>"
$PN"41"48;
%"RES"
"2","(-625,4075)","0","mstr_discrete","I89";
;
CDS_LOCATION"R4D72"
CDS_LIB"mstr_discrete"
$SEC"1"
CDS_SEC"1"
WATTAGE"1/16W"
PACK_TYPE"0402"
PART_NUMBER"G21796-187"
MATERIAL"EMPTY"
TOLERANCE"1%"
VALUE"68.1K"
LOCATION"R4D72";
"A"
$PN"1"39;
"B"
$PN"2"19;
%"GND"
"1","(-625,3850)","0","mstr_symbols","I90";
;
ROOM"PVCCIN_CPU0_PWR_VR"
BOM_COST"PROC_VRD_VCCIN_CPU0"
SIZE"1B"
CDS_LIB"mstr_symbols"
VOLTAGE"0"
BODY_TYPE"PLUMBING"
HDL_POWER"GND";
"A\NAC"19;
%"RES"
"2","(-450,1375)","0","mstr_discrete","I91";
;
CDS_LOCATION"R4D71"
CDS_LIB"mstr_discrete"
$SEC"1"
CDS_SEC"1"
PACK_TYPE"0402"
WATTAGE"1/16W"
TOLERANCE"1%"
VALUE"68.1K"
LOCATION"R4D71"
MATERIAL"EMPTY"
PART_NUMBER"G21796-187";
"A"
$PN"1"47;
"B"
$PN"2"20;
%"GND"
"1","(-450,1200)","0","mstr_symbols","I92";
;
BOM_COST"PROC_VRD_VCCIN_CPU0"
ROOM"PVCCIN_CPU0_PWR_VR"
VOLTAGE"0"
CDS_LIB"mstr_symbols"
SIZE"1B"
BODY_TYPE"PLUMBING"
HDL_POWER"GND";
"A\NAC"20;
%"CAP_A"
"1","(-4125,675)","0","dev_discrete","I93";
;
CDS_SEC"1"
$SEC"1"
CDS_LOCATION"CT40"
ROOM"PVCCIN_CPU0_PWR_VR"
CDS_LIB"dev_discrete"
MATERIAL"X7R"
TOLERANCE"10%"
VOLTAGE"16V"
VALUE"0.1UF"
PACK_TYPE"0402V"
STATUS"NOPOP"
LOCATION"CT40"
PART_NUMBER"A36096-030";
"B"
$PN"2"21;
"A"
$PN"1"35;
%"GND"
"1","(-4125,400)","0","mstr_symbols","I94";
;
CDS_LIB"mstr_symbols"
ROOM"PVCCIN_CPU0_PWR_VR"
BOM_COST"PROC_VRD_VCCIN_CPU0"
SIZE"1B"
VOLTAGE"0"
BODY_TYPE"PLUMBING"
HDL_POWER"GND";
"A\NAC"21;
%"CAP_A"
"1","(-4125,3375)","0","dev_discrete","I96";
;
CDS_SEC"1"
$SEC"1"
CDS_LOCATION"CT39"
ROOM"PVCCIN_CPU0_PWR_VR"
CDS_LIB"dev_discrete"
STATUS"NOPOP"
LOCATION"CT39"
VOLTAGE"16V"
TOLERANCE"10%"
MATERIAL"X7R"
PART_NUMBER"A36096-030"
VALUE"0.1UF"
PACK_TYPE"0402V";
"B"
$PN"2"22;
"A"
$PN"1"49;
%"GND"
"1","(-4125,3125)","0","mstr_symbols","I97";
;
VOLTAGE"0"
SIZE"1B"
BOM_COST"PROC_VRD_VCCIN_CPU0"
ROOM"PVCCIN_CPU0_PWR_VR"
CDS_LIB"mstr_symbols"
BODY_TYPE"PLUMBING"
HDL_POWER"GND";
"A\NAC"22;
%"CAP"
"1","(-2200,3925)","0","mstr_discrete","I99";
;
CDS_SEC"1"
$SEC"1"
CDS_LOCATION"CT37"
ROOM"VDDQ_KLM_PWR_VR"
CDS_LIB"mstr_discrete"
STATUS"NOPOP"
PART_NUMBER"A36096-046"
MATERIAL"X7R"
LOCATION"CT37"
VOLTAGE"50V"
PACK_TYPE"0402LF"
TOLERANCE"10%"
VALUE"1000PF";
"A"
$PN"1"40;
"B"
$PN"2"1;
END.
